# T6G (Grand Teton) — schematic netlist excerpt (pin names and nets, part order shuffled) for the footprints in the layout excerpt that follows; sources: Cadence DE-HDL packaged netlist, KiCad conversion of 04192023_DAF0TMB3IC0_F0TG_MB_C_brd_V02_OCP.brd

C233  Q_CAP  0.001UF 50V 10% EMPTY  pkg C0402  page 54 : A = JTAG_CPU1_TCK ; B = GND
R3102  Q_RES  470 1% CHIP  pkg 0402LF  page 254 : A = LED_P5V ; B = P5V
C547  Q_CAP  10UF 25V 10% X6S  pkg C0805  page 108 : A = P12V_MEM_CPU1 ; B = GND

(kicad_pcb
	(version 20260206)
	(generator "pcbnew")
	(generator_version "10.0")
	(general
		(thickness 1.6)
		(legacy_teardrops no)
	)
	(paper "A4")
	(title_block
		(title "04192023_DAF0TMB3IC0_F0TG_MB_C_brd_V02_OCP.brd")
		(comment 1 "Grand Teton / footprints 7211-7213 of 8354")
	)
	(layers
		(0 "F.Cu" signal "TOP")
		(4 "In1.Cu" signal "GND")
		(6 "In2.Cu" signal "IN1")
		(8 "In3.Cu" signal "GND1")
		(10 "In4.Cu" signal "IN2")
		(12 "In5.Cu" signal "GND2")
		(14 "In6.Cu" signal "IN3")
		(16 "In7.Cu" signal "GND3")
		(18 "In8.Cu" signal "VCC")
		(20 "In9.Cu" signal "VCC1")
		(22 "In10.Cu" signal "GND4")
		(24 "In11.Cu" signal "IN4")
		(26 "In12.Cu" signal "GND5")
		(28 "In13.Cu" signal "IN5")
		(30 "In14.Cu" signal "GND6")
		(32 "In15.Cu" signal "IN6")
		(34 "In16.Cu" signal "GND7")
		(2 "B.Cu" signal "BOTTOM")
		(9 "F.Adhes" user "F.Adhesive")
		(11 "B.Adhes" user "B.Adhesive")
		(13 "F.Paste" user "Package Geometry/Pastemask Top")
		(15 "B.Paste" user "Package Geometry/Pastemask Bottom")
		(5 "F.SilkS" user "Ref Des/Silkscreen Top")
		(7 "B.SilkS" user "Ref Des/Silkscreen Bottom")
		(1 "F.Mask" user "Board Geometry/Soldermask Top")
		(3 "B.Mask" user "Board Geometry/Soldermask Bottom")
		(17 "Dwgs.User" user "User.Drawings")
		(19 "Cmts.User" user "User.Comments")
		(21 "Eco1.User" user "User.Eco1")
		(23 "Eco2.User" user "User.Eco2")
		(25 "Edge.Cuts" user "Board Geometry/Outline")
		(27 "Margin" user)
		(31 "F.CrtYd" user "Package Geometry/Place Bound Top")
		(29 "B.CrtYd" user "Package Geometry/Place Bound Bottom")
		(35 "F.Fab" user "Ref Des/Assembly Top")
		(33 "B.Fab" user "Ref Des/Assembly Bottom")
	)
	(footprint ""
		(layer "B.Cu")
		(at 152.265634 -201.977752 -90)
		(property "Reference" "C233"
			(at 0 0 90)
			(layer "B.SilkS")
			(hide yes)
			(effects
				(font
					(size 1.27 1.27)
				)
				(justify mirror)
			)
		)
		(property "Value" ""
			(at 0 0 90)
			(layer "B.Fab")
			(effects
				(font
					(size 1.27 1.27)
				)
				(justify mirror)
			)
		)
		(duplicate_pad_numbers_are_jumpers no)
		(fp_line
			(start -0.7874 0.4064)
			(end 0.7874 0.4064)
			(stroke
				(width 0.1524)
				(type default)
			)
			(layer "B.SilkS")
		)
		(fp_line
			(start 0.7874 0.4064)
			(end 0.7874 -0.4064)
			(stroke
				(width 0.1524)
				(type default)
			)
			(layer "B.SilkS")
		)
		(fp_line
			(start -0.7874 -0.4064)
			(end -0.7874 0.4064)
			(stroke
				(width 0.1524)
				(type default)
			)
			(layer "B.SilkS")
		)
		(fp_line
			(start 0.7874 -0.4064)
			(end -0.7874 -0.4064)
			(stroke
				(width 0.1524)
				(type default)
			)
			(layer "B.SilkS")
		)
		(fp_line
			(start -0.67945 0.3048)
			(end -0.120396 0.3048)
			(stroke
				(width 0.1)
				(type default)
			)
			(layer "B.Fab")
		)
		(fp_line
			(start -0.120396 0.3048)
			(end -0.120396 0.2794)
			(stroke
				(width 0.1)
				(type default)
			)
			(layer "B.Fab")
		)
		(fp_line
			(start 0.12065 0.3048)
			(end 0.67945 0.3048)
			(stroke
				(width 0.1)
				(type default)
			)
			(layer "B.Fab")
		)
		(fp_line
			(start 0.67945 0.3048)
			(end 0.67945 -0.305054)
			(stroke
				(width 0.1)
				(type default)
			)
			(layer "B.Fab")
		)
		(fp_line
			(start -0.120396 0.2794)
			(end 0.12065 0.2794)
			(stroke
				(width 0.1)
				(type default)
			)
			(layer "B.Fab")
		)
		(fp_line
			(start 0.12065 0.2794)
			(end 0.12065 0.3048)
			(stroke
				(width 0.1)
				(type default)
			)
			(layer "B.Fab")
		)
		(fp_line
			(start -0.12065 -0.2794)
			(end -0.12065 -0.3048)
			(stroke
				(width 0.1)
				(type default)
			)
			(layer "B.Fab")
		)
		(fp_line
			(start 0.12065 -0.2794)
			(end -0.12065 -0.2794)
			(stroke
				(width 0.1)
				(type default)
			)
			(layer "B.Fab")
		)
		(fp_line
			(start -0.67945 -0.3048)
			(end -0.67945 0.3048)
			(stroke
				(width 0.1)
				(type default)
			)
			(layer "B.Fab")
		)
		(fp_line
			(start -0.12065 -0.3048)
			(end -0.67945 -0.3048)
			(stroke
				(width 0.1)
				(type default)
			)
			(layer "B.Fab")
		)
		(fp_line
			(start 0.12065 -0.305054)
			(end 0.12065 -0.2794)
			(stroke
				(width 0.1)
				(type default)
			)
			(layer "B.Fab")
		)
		(fp_line
			(start 0.67945 -0.305054)
			(end 0.12065 -0.305054)
			(stroke
				(width 0.1)
				(type default)
			)
			(layer "B.Fab")
		)
		(pad "1" smd circle
			(at 0.40005 0 90)
			(size 0 0)
			(layers "B.Cu" "B.Mask" "B.Paste")
			(net "JTAG_CPU1_TCK")
		)
		(pad "2" smd circle
			(at -0.40005 0 90)
			(size 0 0)
			(layers "B.Cu" "B.Mask" "B.Paste")
			(net "GND")
		)
	)
	(footprint ""
		(layer "B.Cu")
		(at 194.604132 -192.66027 180)
		(property "Reference" "C547"
			(at 0 0 0)
			(layer "B.SilkS")
			(hide yes)
			(effects
				(font
					(size 1.27 1.27)
				)
				(justify mirror)
			)
		)
		(property "Value" ""
			(at 0 0 0)
			(layer "B.Fab")
			(effects
				(font
					(size 1.27 1.27)
				)
				(justify mirror)
			)
		)
		(duplicate_pad_numbers_are_jumpers no)
		(fp_line
			(start 1.524 0.762)
			(end 1.524 -0.762)
			(stroke
				(width 0.1524)
				(type default)
			)
			(layer "B.SilkS")
		)
		(fp_line
			(start 1.524 -0.762)
			(end -1.524 -0.762)
			(stroke
				(width 0.1524)
				(type default)
			)
			(layer "B.SilkS")
		)
		(fp_line
			(start -1.524 0.762)
			(end 1.524 0.762)
			(stroke
				(width 0.1524)
				(type default)
			)
			(layer "B.SilkS")
		)
		(fp_line
			(start -1.524 -0.762)
			(end -1.524 0.762)
			(stroke
				(width 0.1524)
				(type default)
			)
			(layer "B.SilkS")
		)
		(fp_line
			(start 1.1049 0.724916)
			(end -1.1049 0.724916)
			(stroke
				(width 0.1)
				(type default)
			)
			(layer "B.Fab")
		)
		(fp_line
			(start 1.1049 -0.724916)
			(end 1.1049 0.724916)
			(stroke
				(width 0.1)
				(type default)
			)
			(layer "B.Fab")
		)
		(fp_line
			(start -1.1049 0.724916)
			(end -1.1049 -0.724916)
			(stroke
				(width 0.1)
				(type default)
			)
			(layer "B.Fab")
		)
		(fp_line
			(start -1.1049 -0.724916)
			(end 1.1049 -0.724916)
			(stroke
				(width 0.1)
				(type default)
			)
			(layer "B.Fab")
		)
		(pad "1" smd rect
			(at 0.889 0 180)
			(size 1.016 1.27)
			(layers "B.Cu" "B.Mask" "B.Paste")
			(net "P12V_MEM_CPU1")
		)
		(pad "2" smd rect
			(at -0.889 0 180)
			(size 1.016 1.27)
			(layers "B.Cu" "B.Mask" "B.Paste")
			(net "GND")
		)
	)
	(footprint ""
		(layer "B.Cu")
		(at 314.475876 -66.708782 90)
		(property "Reference" "R3102"
			(at 0 0 90)
			(layer "B.SilkS")
			(hide yes)
			(effects
				(font
					(size 1.27 1.27)
				)
				(justify mirror)
			)
		)
		(property "Value" ""
			(at 0 0 90)
			(layer "B.Fab")
			(effects
				(font
					(size 1.27 1.27)
				)
				(justify mirror)
			)
		)
		(duplicate_pad_numbers_are_jumpers no)
		(fp_line
			(start 0.7874 -0.4064)
			(end -0.7874 -0.4064)
			(stroke
				(width 0.1524)
				(type default)
			)
			(layer "B.SilkS")
		)
		(fp_line
			(start -0.7874 -0.4064)
			(end -0.7874 0.4064)
			(stroke
				(width 0.1524)
				(type default)
			)
			(layer "B.SilkS")
		)
		(fp_line
			(start 0.7874 0.4064)
			(end 0.7874 -0.4064)
			(stroke
				(width 0.1524)
				(type default)
			)
			(layer "B.SilkS")
		)
		(fp_line
			(start -0.7874 0.4064)
			(end 0.7874 0.4064)
			(stroke
				(width 0.1524)
				(type default)
			)
			(layer "B.SilkS")
		)
		(fp_line
			(start 0.67945 -0.305054)
			(end 0.12065 -0.305054)
			(stroke
				(width 0.1)
				(type default)
			)
			(layer "B.Fab")
		)
		(fp_line
			(start 0.12065 -0.305054)
			(end 0.12065 -0.2794)
			(stroke
				(width 0.1)
				(type default)
			)
			(layer "B.Fab")
		)
		(fp_line
			(start -0.12065 -0.3048)
			(end -0.67945 -0.3048)
			(stroke
				(width 0.1)
				(type default)
			)
			(layer "B.Fab")
		)
		(fp_line
			(start -0.67945 -0.3048)
			(end -0.67945 0.3048)
			(stroke
				(width 0.1)
				(type default)
			)
			(layer "B.Fab")
		)
		(fp_line
			(start 0.12065 -0.2794)
			(end -0.12065 -0.2794)
			(stroke
				(width 0.1)
				(type default)
			)
			(layer "B.Fab")
		)
		(fp_line
			(start -0.12065 -0.2794)
			(end -0.12065 -0.3048)
			(stroke
				(width 0.1)
				(type default)
			)
			(layer "B.Fab")
		)
		(fp_line
			(start 0.12065 0.2794)
			(end 0.12065 0.3048)
			(stroke
				(width 0.1)
				(type default)
			)
			(layer "B.Fab")
		)
		(fp_line
			(start -0.120396 0.2794)
			(end 0.12065 0.2794)
			(stroke
				(width 0.1)
				(type default)
			)
			(layer "B.Fab")
		)
		(fp_line
			(start 0.67945 0.3048)
			(end 0.67945 -0.305054)
			(stroke
				(width 0.1)
				(type default)
			)
			(layer "B.Fab")
		)
		(fp_line
			(start 0.12065 0.3048)
			(end 0.67945 0.3048)
			(stroke
				(width 0.1)
				(type default)
			)
			(layer "B.Fab")
		)
		(fp_line
			(start -0.120396 0.3048)
			(end -0.120396 0.2794)
			(stroke
				(width 0.1)
				(type default)
			)
			(layer "B.Fab")
		)
		(fp_line
			(start -0.67945 0.3048)
			(end -0.120396 0.3048)
			(stroke
				(width 0.1)
				(type default)
			)
			(layer "B.Fab")
		)
		(pad "1" smd circle
			(at 0.40005 0 270)
			(size 0 0)
			(layers "B.Cu" "B.Mask" "B.Paste")
			(net "LED_P5V")
		)
		(pad "2" smd circle
			(at -0.40005 0 270)
			(size 0 0)
			(layers "B.Cu" "B.Mask" "B.Paste")
			(net "P5V")
		)
	)
)
